# T6G (Grand Teton) — schematic netlist excerpt (pin names and nets, part order shuffled) for the footprints in the layout excerpt that follows; sources: Cadence DE-HDL packaged netlist, KiCad conversion of 04192023_DAF0TMB3IC0_F0TG_MB_C_brd_V02_OCP.brd

C6636  Q_CAP_DIFFBUS  DIFF BUS_0.22UF 6.3V 20% X6S  pkg C0201  page 319 : \1\ = P5E_CPU1_P0_TX_BUF_C_DN<3> ; \2\ = P5E_CPU1_P0_TX_BUF_DN<3>
C85  Q_CAP  0.001UF 50V 10% X7R  pkg C0402  page 172 : A = HDT_HDR_TRST_N ; B = GND

Q75  MOSFET_NCH_DUAL  PJT138K IC  pkg SOT363XD  page 127
  S1  = GND
  G1  = FM_SMB_1_ALERT_GPU_N
  D2  = FM_SMB_1_ALERT_GPU_ISO_N
  S2  = GND
  G2  = FM_SMB_1_ALERT_GPU
  D1  = FM_SMB_1_ALERT_GPU

(kicad_pcb
	(version 20260206)
	(generator "pcbnew")
	(generator_version "10.0")
	(general
		(thickness 1.6)
		(legacy_teardrops no)
	)
	(paper "A4")
	(title_block
		(title "04192023_DAF0TMB3IC0_F0TG_MB_C_brd_V02_OCP.brd")
		(comment 1 "Grand Teton / footprints 2829-2831 of 8354")
	)
	(layers
		(0 "F.Cu" signal "TOP")
		(4 "In1.Cu" signal "GND")
		(6 "In2.Cu" signal "IN1")
		(8 "In3.Cu" signal "GND1")
		(10 "In4.Cu" signal "IN2")
		(12 "In5.Cu" signal "GND2")
		(14 "In6.Cu" signal "IN3")
		(16 "In7.Cu" signal "GND3")
		(18 "In8.Cu" signal "VCC")
		(20 "In9.Cu" signal "VCC1")
		(22 "In10.Cu" signal "GND4")
		(24 "In11.Cu" signal "IN4")
		(26 "In12.Cu" signal "GND5")
		(28 "In13.Cu" signal "IN5")
		(30 "In14.Cu" signal "GND6")
		(32 "In15.Cu" signal "IN6")
		(34 "In16.Cu" signal "GND7")
		(2 "B.Cu" signal "BOTTOM")
		(9 "F.Adhes" user "F.Adhesive")
		(11 "B.Adhes" user "B.Adhesive")
		(13 "F.Paste" user "Package Geometry/Pastemask Top")
		(15 "B.Paste" user "Package Geometry/Pastemask Bottom")
		(5 "F.SilkS" user "Ref Des/Silkscreen Top")
		(7 "B.SilkS" user "Ref Des/Silkscreen Bottom")
		(1 "F.Mask" user "Board Geometry/Soldermask Top")
		(3 "B.Mask" user "Board Geometry/Soldermask Bottom")
		(17 "Dwgs.User" user "User.Drawings")
		(19 "Cmts.User" user "User.Comments")
		(21 "Eco1.User" user "User.Eco1")
		(23 "Eco2.User" user "User.Eco2")
		(25 "Edge.Cuts" user "Board Geometry/Outline")
		(27 "Margin" user)
		(31 "F.CrtYd" user "Package Geometry/Place Bound Top")
		(29 "B.CrtYd" user "Package Geometry/Place Bound Bottom")
		(35 "F.Fab" user "Ref Des/Assembly Top")
		(33 "B.Fab" user "Ref Des/Assembly Bottom")
	)
	(footprint ""
		(layer "F.Cu")
		(at 405.753062 -57.2135)
		(property "Reference" "C85"
			(at 0 0 0)
			(layer "F.SilkS")
			(hide yes)
			(effects
				(font
					(size 1.27 1.27)
				)
			)
		)
		(property "Value" ""
			(at 0 0 0)
			(layer "F.Fab")
			(effects
				(font
					(size 1.27 1.27)
				)
			)
		)
		(duplicate_pad_numbers_are_jumpers no)
		(fp_line
			(start -0.7874 -0.4064)
			(end 0.7874 -0.4064)
			(stroke
				(width 0.1524)
				(type default)
			)
			(layer "F.SilkS")
		)
		(fp_line
			(start -0.7874 0.4064)
			(end -0.7874 -0.4064)
			(stroke
				(width 0.1524)
				(type default)
			)
			(layer "F.SilkS")
		)
		(fp_line
			(start 0.7874 -0.4064)
			(end 0.7874 0.4064)
			(stroke
				(width 0.1524)
				(type default)
			)
			(layer "F.SilkS")
		)
		(fp_line
			(start 0.7874 0.4064)
			(end -0.7874 0.4064)
			(stroke
				(width 0.1524)
				(type default)
			)
			(layer "F.SilkS")
		)
		(fp_line
			(start -0.67945 -0.305054)
			(end -0.12065 -0.305054)
			(stroke
				(width 0.1)
				(type default)
			)
			(layer "F.Fab")
		)
		(fp_line
			(start -0.67945 0.3048)
			(end -0.67945 -0.305054)
			(stroke
				(width 0.1)
				(type default)
			)
			(layer "F.Fab")
		)
		(fp_line
			(start -0.12065 -0.305054)
			(end -0.12065 -0.2794)
			(stroke
				(width 0.1)
				(type default)
			)
			(layer "F.Fab")
		)
		(fp_line
			(start -0.12065 -0.2794)
			(end 0.12065 -0.2794)
			(stroke
				(width 0.1)
				(type default)
			)
			(layer "F.Fab")
		)
		(fp_line
			(start -0.12065 0.2794)
			(end -0.12065 0.3048)
			(stroke
				(width 0.1)
				(type default)
			)
			(layer "F.Fab")
		)
		(fp_line
			(start -0.12065 0.3048)
			(end -0.67945 0.3048)
			(stroke
				(width 0.1)
				(type default)
			)
			(layer "F.Fab")
		)
		(fp_line
			(start 0.120396 0.2794)
			(end -0.12065 0.2794)
			(stroke
				(width 0.1)
				(type default)
			)
			(layer "F.Fab")
		)
		(fp_line
			(start 0.120396 0.3048)
			(end 0.120396 0.2794)
			(stroke
				(width 0.1)
				(type default)
			)
			(layer "F.Fab")
		)
		(fp_line
			(start 0.12065 -0.3048)
			(end 0.67945 -0.3048)
			(stroke
				(width 0.1)
				(type default)
			)
			(layer "F.Fab")
		)
		(fp_line
			(start 0.12065 -0.2794)
			(end 0.12065 -0.3048)
			(stroke
				(width 0.1)
				(type default)
			)
			(layer "F.Fab")
		)
		(fp_line
			(start 0.67945 -0.3048)
			(end 0.67945 0.3048)
			(stroke
				(width 0.1)
				(type default)
			)
			(layer "F.Fab")
		)
		(fp_line
			(start 0.67945 0.3048)
			(end 0.120396 0.3048)
			(stroke
				(width 0.1)
				(type default)
			)
			(layer "F.Fab")
		)
		(pad "1" smd circle
			(at -0.40005 0)
			(size 0 0)
			(layers "F.Cu" "F.Mask" "F.Paste")
			(net "HDT_HDR_TRST_N")
		)
		(pad "2" smd circle
			(at 0.40005 0)
			(size 0 0)
			(layers "F.Cu" "F.Mask" "F.Paste")
			(net "GND")
		)
	)
	(footprint ""
		(layer "F.Cu")
		(at 115.189 -415.29 180)
		(property "Reference" "Q75"
			(at -3.272282 -1.210564 90)
			(unlocked yes)
			(layer "F.SilkS")
			(effects
				(font
					(size 0.7874 0.5842)
					(thickness 0.1524)
				)
				(justify left)
			)
		)
		(property "Value" ""
			(at 0 0 180)
			(layer "F.Fab")
			(effects
				(font
					(size 1.27 1.27)
				)
			)
		)
		(duplicate_pad_numbers_are_jumpers no)
		(fp_line
			(start 1.332738 1.100074)
			(end -1.332738 1.100074)
			(stroke
				(width 0.1524)
				(type default)
			)
			(layer "F.SilkS")
		)
		(fp_line
			(start 1.332738 -1.100074)
			(end 1.332738 1.100074)
			(stroke
				(width 0.1524)
				(type default)
			)
			(layer "F.SilkS")
		)
		(fp_line
			(start 0.4826 -1.100074)
			(end 1.332738 -1.100074)
			(stroke
				(width 0.1524)
				(type default)
			)
			(layer "F.SilkS")
		)
		(fp_line
			(start 0 -0.541274)
			(end 0.4826 -1.100074)
			(stroke
				(width 0.1524)
				(type default)
			)
			(layer "F.SilkS")
		)
		(fp_line
			(start -0.4826 -1.100074)
			(end 0 -0.541274)
			(stroke
				(width 0.1524)
				(type default)
			)
			(layer "F.SilkS")
		)
		(fp_line
			(start -1.332738 1.100074)
			(end -1.332738 -1.100074)
			(stroke
				(width 0.1524)
				(type default)
			)
			(layer "F.SilkS")
		)
		(fp_line
			(start -1.332738 -1.100074)
			(end -0.4826 -1.100074)
			(stroke
				(width 0.1524)
				(type default)
			)
			(layer "F.SilkS")
		)
		(fp_poly
			(pts
				(xy -1.533144 -0.649986) (xy -2.2352 -0.298958) (xy -2.2352 -1.001014)
			)
			(stroke
				(width 0)
				(type default)
			)
			(fill yes)
			(layer "F.SilkS")
		)
		(fp_line
			(start 0.674878 1.100074)
			(end -0.674878 1.100074)
			(stroke
				(width 0.1)
				(type default)
			)
			(layer "F.Fab")
		)
		(fp_line
			(start 0.674878 -1.100074)
			(end 0.674878 1.100074)
			(stroke
				(width 0.1)
				(type default)
			)
			(layer "F.Fab")
		)
		(fp_line
			(start -0.674878 1.100074)
			(end -0.674878 -1.100074)
			(stroke
				(width 0.1)
				(type default)
			)
			(layer "F.Fab")
		)
		(fp_line
			(start -0.674878 -1.100074)
			(end 0.674878 -1.100074)
			(stroke
				(width 0.1)
				(type default)
			)
			(layer "F.Fab")
		)
		(fp_poly
			(pts
				(xy -2.2352 -0.298958) (xy -2.2352 -1.001014) (xy -1.533144 -0.649986)
			)
			(stroke
				(width 0)
				(type default)
			)
			(fill yes)
			(layer "F.Fab")
		)
		(pad "1" smd rect
			(at -0.94996 -0.649986 270)
			(size 0.4318 0.508)
			(layers "F.Cu" "F.Mask" "F.Paste")
			(net "GND")
		)
		(pad "2" smd rect
			(at -0.94996 0 270)
			(size 0.4318 0.508)
			(layers "F.Cu" "F.Mask" "F.Paste")
			(net "FM_SMB_1_ALERT_GPU_N")
		)
		(pad "3" smd rect
			(at -0.94996 0.649986 270)
			(size 0.4318 0.508)
			(layers "F.Cu" "F.Mask" "F.Paste")
			(net "FM_SMB_1_ALERT_GPU_ISO_N")
		)
		(pad "4" smd rect
			(at 0.94996 0.649986 270)
			(size 0.4318 0.508)
			(layers "F.Cu" "F.Mask" "F.Paste")
			(net "GND")
		)
		(pad "5" smd rect
			(at 0.94996 0 270)
			(size 0.4318 0.508)
			(layers "F.Cu" "F.Mask" "F.Paste")
			(net "FM_SMB_1_ALERT_GPU")
		)
		(pad "6" smd rect
			(at 0.94996 -0.649986 270)
			(size 0.4318 0.508)
			(layers "F.Cu" "F.Mask" "F.Paste")
			(net "FM_SMB_1_ALERT_GPU")
		)
	)
	(footprint ""
		(layer "F.Cu")
		(at 56.958484 -408.517344 -90)
		(property "Reference" "C6636"
			(at 0 0 270)
			(layer "F.SilkS")
			(hide yes)
			(effects
				(font
					(size 1.27 1.27)
				)
			)
		)
		(property "Value" ""
			(at 0 0 270)
			(layer "F.Fab")
			(effects
				(font
					(size 1.27 1.27)
				)
			)
		)
		(duplicate_pad_numbers_are_jumpers no)
		(fp_line
			(start -0.299974 0.150114)
			(end -0.299974 -0.150114)
			(stroke
				(width 0.1)
				(type default)
			)
			(layer "F.Fab")
		)
		(fp_line
			(start 0.299974 0.150114)
			(end -0.299974 0.150114)
			(stroke
				(width 0.1)
				(type default)
			)
			(layer "F.Fab")
		)
		(fp_line
			(start -0.299974 -0.150114)
			(end 0.299974 -0.150114)
			(stroke
				(width 0.1)
				(type default)
			)
			(layer "F.Fab")
		)
		(fp_line
			(start 0.299974 -0.150114)
			(end 0.299974 0.150114)
			(stroke
				(width 0.1)
				(type default)
			)
			(layer "F.Fab")
		)
		(pad "1" smd rect
			(at -0.2667 0 270)
			(size 0.3048 0.381)
			(layers "F.Cu" "F.Mask" "F.Paste")
			(net "P5E_CPU1_P0_TX_BUF_C_DN<3>")
		)
		(pad "2" smd rect
			(at 0.2667 0 270)
			(size 0.3048 0.381)
			(layers "F.Cu" "F.Mask" "F.Paste")
			(net "P5E_CPU1_P0_TX_BUF_DN<3>")
		)
	)
)
